(kicad_pcb
	(version 20241229)
	(generator "pcbnew")
	(generator_version "9.0")
	(general
		(thickness 1.6296)
		(legacy_teardrops no)
	)
	(paper "A3")
	(title_block
		(title "Thunderbolt to 10GbE adapter")
		(date "2026-04-21")
		(rev "1.1.0")
		(company "Antmicro Ltd")
		(comment 1 "www.antmicro.com")
		(comment 9 "footprints 146-150 of 703")
	)
	(layers
		(0 "F.Cu" signal)
		(4 "In1.Cu" signal)
		(6 "In2.Cu" signal)
		(8 "In3.Cu" signal)
		(10 "In4.Cu" signal)
		(12 "In5.Cu" signal)
		(14 "In6.Cu" signal)
		(2 "B.Cu" signal)
		(9 "F.Adhes" user "F.Adhesive")
		(11 "B.Adhes" user "B.Adhesive")
		(13 "F.Paste" user)
		(15 "B.Paste" user)
		(5 "F.SilkS" user "F.Silkscreen")
		(7 "B.SilkS" user "B.Silkscreen")
		(1 "F.Mask" user)
		(3 "B.Mask" user)
		(17 "Dwgs.User" user "User.Drawings")
		(19 "Cmts.User" user "User.Comments")
		(21 "Eco1.User" user "User.Eco1")
		(23 "Eco2.User" user "User.Eco2")
		(25 "Edge.Cuts" user)
		(27 "Margin" user)
		(31 "F.CrtYd" user "F.Courtyard")
		(29 "B.CrtYd" user "B.Courtyard")
		(35 "F.Fab" user)
		(33 "B.Fab" user)
	)
	(footprint "antmicro-footprints:R_0402_1005Metric"
		(layer "F.Cu")
		(at 147.1 128.2 -90)
		(descr "Resistor SMD 0402")
		(tags "resistor SMD 0402")
		(property "Reference" "R79"
			(at 3.2 -0.4 270)
			(layer "F.SilkS")
			(effects
				(font
					(size 0.7 0.7)
					(thickness 0.15)
				)
				(justify left bottom)
			)
		)
		(property "Value" "R_3k3_0402"
			(at -1.011843 1.772047 270)
			(layer "F.Fab")
			(effects
				(font
					(size 0.7 0.7)
					(thickness 0.15)
				)
				(justify left bottom)
			)
		)
		(property "Datasheet" "https://www.bourns.com/docs/product-datasheets/cr.pdf"
			(at 0 0 270)
			(layer "F.Fab")
			(hide yes)
			(effects
				(font
					(size 1.27 1.27)
					(thickness 0.15)
				)
			)
		)
		(property "Description" "SMD Chip Resistor, 3.3 kohm, ± 1%, 63 mW, 0402 [1005 Metric], Thick Film, General Purpose"
			(at 0 0 270)
			(layer "F.Fab")
			(hide yes)
			(effects
				(font
					(size 1.27 1.27)
					(thickness 0.15)
				)
			)
		)
		(property "MPN" "CR0402-FX-3301GLF"
			(at 0 0 270)
			(unlocked yes)
			(layer "F.Fab")
			(hide yes)
			(effects
				(font
					(size 1 1)
					(thickness 0.15)
				)
			)
		)
		(property "Manufacturer" "Bourns"
			(at 0 0 270)
			(unlocked yes)
			(layer "F.Fab")
			(hide yes)
			(effects
				(font
					(size 1 1)
					(thickness 0.15)
				)
			)
		)
		(property "License" "Apache-2.0"
			(at 0 0 270)
			(unlocked yes)
			(layer "F.Fab")
			(hide yes)
			(effects
				(font
					(size 1 1)
					(thickness 0.15)
				)
			)
		)
		(property "Val" "3k3"
			(at 0 0 270)
			(unlocked yes)
			(layer "F.Fab")
			(hide yes)
			(effects
				(font
					(size 1 1)
					(thickness 0.15)
				)
			)
		)
		(property "Tolerance" "1%"
			(at 0 0 270)
			(unlocked yes)
			(layer "F.Fab")
			(hide yes)
			(effects
				(font
					(size 1 1)
					(thickness 0.15)
				)
			)
		)
		(property "Author" "Antmicro"
			(at 0 0 270)
			(unlocked yes)
			(layer "F.Fab")
			(hide yes)
			(effects
				(font
					(size 1 1)
					(thickness 0.15)
				)
			)
		)
		(sheetname "/TB flash memory/")
		(sheetfile "flash-memory.kicad_sch")
		(attr smd)
		(fp_rect
			(start -0.925 -0.47)
			(end 0.925 0.47)
			(stroke
				(width 0.05)
				(type default)
			)
			(fill no)
			(layer "F.CrtYd")
		)
		(fp_rect
			(start -0.5 -0.25)
			(end 0.5 0.25)
			(stroke
				(width 0.15)
				(type solid)
			)
			(fill no)
			(layer "F.Fab")
		)
		(fp_text user "Author: Antmicro"
			(at -0.95 4.169 270)
			(layer "F.Fab")
			(effects
				(font
					(size 0.7 0.7)
					(thickness 0.15)
				)
				(justify left bottom)
			)
		)
		(fp_text user "License: Apache-2.0"
			(at -0.95 5.169 270)
			(layer "F.Fab")
			(effects
				(font
					(size 0.7 0.7)
					(thickness 0.15)
				)
				(justify left bottom)
			)
		)
		(fp_text user "${REFERENCE}"
			(at -0.95 3.168 270)
			(layer "F.Fab")
			(effects
				(font
					(size 0.7 0.7)
					(thickness 0.15)
				)
				(justify left bottom)
			)
		)
		(pad "1" smd roundrect
			(at -0.48 0 270)
			(size 0.59 0.64)
			(layers "F.Cu" "F.Mask" "F.Paste")
			(roundrect_rratio 0.25)
			(net 357 "/PD and TB DC-DC/TB_FLASH.MISO")
			(pintype "passive")
		)
		(pad "2" smd roundrect
			(at 0.48 0 270)
			(size 0.59 0.64)
			(layers "F.Cu" "F.Mask" "F.Paste")
			(roundrect_rratio 0.25)
			(net 57 "+3V3_TB")
			(pintype "passive")
		)
	)
	(footprint "antmicro-footprints:L_Bourns-SRP2512A"
		(layer "F.Cu")
		(at 154.675 96.385 90)
		(property "Reference" "L10"
			(at -19.625001 23.294999 270)
			(layer "F.SilkS")
			(effects
				(font
					(size 0.7 0.7)
					(thickness 0.15)
				)
			)
		)
		(property "Value" "L_4u7_1.55A_Bourns-SRP2512A"
			(at 0 2.25 270)
			(layer "F.Fab")
			(effects
				(font
					(size 0.7 0.7)
					(thickness 0.15)
				)
				(justify left bottom)
			)
		)
		(property "Datasheet" "https://www.bourns.com/docs/Product-Datasheets/srp2512a.pdf"
			(at 0 0 90)
			(layer "F.Fab")
			(hide yes)
			(effects
				(font
					(size 1.27 1.27)
					(thickness 0.15)
				)
			)
		)
		(property "Description" "4.7 µH Shielded Drum Core, Wirewound Inductor 1.55 A 235mOhm Max 1008 (2520 Metric)"
			(at 0 0 90)
			(layer "F.Fab")
			(hide yes)
			(effects
				(font
					(size 1.27 1.27)
					(thickness 0.15)
				)
			)
		)
		(property "Val" "4u7/1.55A"
			(at 0 0 90)
			(unlocked yes)
			(layer "F.Fab")
			(hide yes)
			(effects
				(font
					(size 1 1)
					(thickness 0.15)
				)
			)
		)
		(property "Manufacturer" "Bourns"
			(at 0 0 90)
			(unlocked yes)
			(layer "F.Fab")
			(hide yes)
			(effects
				(font
					(size 1 1)
					(thickness 0.15)
				)
			)
		)
		(property "MPN" "SRP2512A-4R7M"
			(at 0 0 90)
			(unlocked yes)
			(layer "F.Fab")
			(hide yes)
			(effects
				(font
					(size 1 1)
					(thickness 0.15)
				)
			)
		)
		(property "ISat" "1.9 A"
			(at 0 0 90)
			(unlocked yes)
			(layer "F.Fab")
			(hide yes)
			(effects
				(font
					(size 1 1)
					(thickness 0.15)
				)
			)
		)
		(property "IMax" "1.55 A"
			(at 0 0 90)
			(unlocked yes)
			(layer "F.Fab")
			(hide yes)
			(effects
				(font
					(size 1 1)
					(thickness 0.15)
				)
			)
		)
		(property "Size" "2.5x2.0"
			(at 0 0 90)
			(unlocked yes)
			(layer "F.Fab")
			(hide yes)
			(effects
				(font
					(size 1 1)
					(thickness 0.15)
				)
			)
		)
		(property "Author" "Antmicro"
			(at 0 0 90)
			(unlocked yes)
			(layer "F.Fab")
			(hide yes)
			(effects
				(font
					(size 1 1)
					(thickness 0.15)
				)
			)
		)
		(property "License" "Apache-2.0"
			(at 0 0 90)
			(unlocked yes)
			(layer "F.Fab")
			(hide yes)
			(effects
				(font
					(size 1 1)
					(thickness 0.15)
				)
			)
		)
		(sheetname "/X710-AT2 power/")
		(sheetfile "x710-at2-power.kicad_sch")
		(attr smd)
		(fp_line
			(start -0.35 -1)
			(end 0.35 -1)
			(stroke
				(width 0.15)
				(type solid)
			)
			(layer "F.SilkS")
		)
		(fp_line
			(start -0.351 1)
			(end 0.349 1)
			(stroke
				(width 0.15)
				(type solid)
			)
			(layer "F.SilkS")
		)
		(fp_rect
			(start -1.65 -1.3)
			(end 1.65 1.3)
			(stroke
				(width 0.05)
				(type solid)
			)
			(fill no)
			(layer "F.CrtYd")
		)
		(fp_text user "${REFERENCE}"
			(at -2.575 3.475 90)
			(layer "F.Fab")
			(effects
				(font
					(size 0.7 0.7)
					(thickness 0.15)
				)
				(justify left bottom)
			)
		)
		(fp_text user "Author: Antmicro"
			(at -2.575 4.675 90)
			(layer "F.Fab")
			(effects
				(font
					(size 0.7 0.7)
					(thickness 0.15)
				)
				(justify left bottom)
			)
		)
		(fp_text user "License: Apache-2.0"
			(at -2.575 5.875 90)
			(layer "F.Fab")
			(effects
				(font
					(size 0.7 0.7)
					(thickness 0.15)
				)
				(justify left bottom)
			)
		)
		(pad "1" smd roundrect
			(at -1 0 180)
			(size 2 0.8)
			(layers "F.Cu" "F.Mask" "F.Paste")
			(roundrect_rratio 0.1)
			(net 136 "+1V0")
			(pintype "passive")
		)
		(pad "2" smd roundrect
			(at 1 0 180)
			(size 2 0.8)
			(layers "F.Cu" "F.Mask" "F.Paste")
			(roundrect_rratio 0.1)
			(net 21 "XFI_PVDD")
			(pintype "passive")
		)
	)
	(footprint "antmicro-footprints:R_0402_1005Metric"
		(layer "F.Cu")
		(at 171.6 72.1 90)
		(descr "Resistor SMD 0402")
		(tags "resistor SMD 0402")
		(property "Reference" "R185"
			(at 0.9 0.4 90)
			(layer "F.SilkS")
			(effects
				(font
					(size 0.7 0.7)
					(thickness 0.15)
				)
				(justify left bottom)
			)
		)
		(property "Value" "R_10R_0402"
			(at -1.011843 1.772047 90)
			(layer "F.Fab")
			(effects
				(font
					(size 0.7 0.7)
					(thickness 0.15)
				)
				(justify left bottom)
			)
		)
		(property "Datasheet" "https://www.bourns.com/docs/product-datasheets/cr.pdf"
			(at 0 0 90)
			(layer "F.Fab")
			(hide yes)
			(effects
				(font
					(size 1.27 1.27)
					(thickness 0.15)
				)
			)
		)
		(property "Description" "SMD Chip Resistor, 10 ohm, ± 1%, 62.5 mW, 0402 [1005 Metric], Thick Film, General Purpose"
			(at 0 0 90)
			(layer "F.Fab")
			(hide yes)
			(effects
				(font
					(size 1.27 1.27)
					(thickness 0.15)
				)
			)
		)
		(property "MPN" "CR0402-FX-10R0GLF"
			(at 0 0 90)
			(unlocked yes)
			(layer "F.Fab")
			(hide yes)
			(effects
				(font
					(size 1 1)
					(thickness 0.15)
				)
			)
		)
		(property "Manufacturer" "Bourns"
			(at 0 0 90)
			(unlocked yes)
			(layer "F.Fab")
			(hide yes)
			(effects
				(font
					(size 1 1)
					(thickness 0.15)
				)
			)
		)
		(property "License" "Apache-2.0"
			(at 0 0 90)
			(unlocked yes)
			(layer "F.Fab")
			(hide yes)
			(effects
				(font
					(size 1 1)
					(thickness 0.15)
				)
			)
		)
		(property "Author" "Antmicro"
			(at 0 0 90)
			(unlocked yes)
			(layer "F.Fab")
			(hide yes)
			(effects
				(font
					(size 1 1)
					(thickness 0.15)
				)
			)
		)
		(property "Val" "10R"
			(at 0 0 90)
			(unlocked yes)
			(layer "F.Fab")
			(hide yes)
			(effects
				(font
					(size 1 1)
					(thickness 0.15)
				)
			)
		)
		(property "Tolerance" "1%"
			(at 0 0 90)
			(unlocked yes)
			(layer "F.Fab")
			(hide yes)
			(effects
				(font
					(size 1 1)
					(thickness 0.15)
				)
			)
		)
		(sheetname "/X710-AT2 10GbE/")
		(sheetfile "x710-at2-10gbe.kicad_sch")
		(attr smd)
		(fp_rect
			(start -0.925 -0.47)
			(end 0.925 0.47)
			(stroke
				(width 0.05)
				(type default)
			)
			(fill no)
			(layer "F.CrtYd")
		)
		(fp_rect
			(start -0.5 -0.25)
			(end 0.5 0.25)
			(stroke
				(width 0.15)
				(type solid)
			)
			(fill no)
			(layer "F.Fab")
		)
		(fp_text user "${REFERENCE}"
			(at -0.95 3.168 90)
			(layer "F.Fab")
			(effects
				(font
					(size 0.7 0.7)
					(thickness 0.15)
				)
				(justify left bottom)
			)
		)
		(fp_text user "License: Apache-2.0"
			(at -0.95 5.169 90)
			(layer "F.Fab")
			(effects
				(font
					(size 0.7 0.7)
					(thickness 0.15)
				)
				(justify left bottom)
			)
		)
		(fp_text user "Author: Antmicro"
			(at -0.95 4.169 90)
			(layer "F.Fab")
			(effects
				(font
					(size 0.7 0.7)
					(thickness 0.15)
				)
				(justify left bottom)
			)
		)
		(pad "1" smd roundrect
			(at -0.48 0 90)
			(size 0.59 0.64)
			(layers "F.Cu" "F.Mask" "F.Paste")
			(roundrect_rratio 0.25)
			(net 122 "/X710-AT2 10GbE/MDIO0_I2C0.MDIO")
			(pintype "passive")
		)
		(pad "2" smd roundrect
			(at 0.48 0 90)
			(size 0.59 0.64)
			(layers "F.Cu" "F.Mask" "F.Paste")
			(roundrect_rratio 0.25)
			(net 102 "/X710-AT2 10GbE/MDIO0_SDA0")
			(pintype "passive")
		)
	)
	(footprint "antmicro-footprints:Mech_Lightpipe_Mentor_1271.1001"
		(layer "F.Cu")
		(at 135 147.813534 180)
		(descr "1x1  Horizontal Light Guide with transparent pipe")
		(tags "Horizontal, THT, MECHANICAL, MODULE")
		(property "Reference" "H3"
			(at 1.85 -3.386466 0)
			(unlocked yes)
			(layer "F.SilkS")
			(effects
				(font
					(size 0.7 0.7)
					(thickness 0.15)
				)
				(justify left bottom)
			)
		)
		(property "Value" "Lightpipe_Mentor_1271.1001"
			(at 0 9 180)
			(unlocked yes)
			(layer "F.Fab")
			(effects
				(font
					(size 0.7 0.7)
					(thickness 0.15)
				)
				(justify left bottom)
			)
		)
		(property "Datasheet" "https://www.mentor.de.com/productpdfs/ll/ll14-20.pdf"
			(at 0 0 180)
			(layer "F.Fab")
			(hide yes)
			(effects
				(font
					(size 1.27 1.27)
					(thickness 0.15)
				)
			)
		)
		(property "Description" "Light Pipe, 14.45 mm, 1 Pipe, Circular, PC Board, Transparent"
			(at 0 0 180)
			(layer "F.Fab")
			(hide yes)
			(effects
				(font
					(size 1.27 1.27)
					(thickness 0.15)
				)
			)
		)
		(property "MPN" "1271.1001"
			(at 0 0 180)
			(unlocked yes)
			(layer "F.Fab")
			(hide yes)
			(effects
				(font
					(size 1 1)
					(thickness 0.15)
				)
			)
		)
		(property "Manufacturer" "Mentor Worldwide"
			(at 0 0 180)
			(unlocked yes)
			(layer "F.Fab")
			(hide yes)
			(effects
				(font
					(size 1 1)
					(thickness 0.15)
				)
			)
		)
		(property "Author" "Antmicro"
			(at 0 0 180)
			(unlocked yes)
			(layer "F.Fab")
			(hide yes)
			(effects
				(font
					(size 1 1)
					(thickness 0.15)
				)
			)
		)
		(property "License" "Apache-2.0"
			(at 0 0 180)
			(unlocked yes)
			(layer "F.Fab")
			(hide yes)
			(effects
				(font
					(size 1 1)
					(thickness 0.15)
				)
			)
		)
		(sheetname "/")
		(sheetfile "thunderbolt-to-10gbe-adapter.kicad_sch")
		(attr through_hole)
		(fp_rect
			(start -1.55 -2.1)
			(end 1.55 1.3)
			(stroke
				(width 0.05)
				(type solid)
			)
			(fill no)
			(layer "F.SilkS")
		)
		(fp_rect
			(start -1.75 -2.3)
			(end 1.75 1.475)
			(stroke
				(width 0.05)
				(type solid)
			)
			(fill no)
			(layer "F.CrtYd")
		)
		(fp_rect
			(start -1.4732 -8.128)
			(end 1.4732 6.2484)
			(stroke
				(width 0.15)
				(type solid)
			)
			(fill no)
			(layer "F.Fab")
		)
		(fp_text user "License: Apache-2.0"
			(at -1.8 11.7 180)
			(layer "F.Fab")
			(effects
				(font
					(size 0.7 0.7)
					(thickness 0.15)
				)
				(justify left bottom)
			)
		)
		(fp_text user "Author: Antmicro"
			(at -1.8 10.5 180)
			(layer "F.Fab")
			(effects
				(font
					(size 0.7 0.7)
					(thickness 0.15)
				)
				(justify left bottom)
			)
		)
		(fp_text user "${REFERENCE}"
			(at -1.8 12.9 180)
			(layer "F.Fab")
			(effects
				(font
					(size 0.7 0.7)
					(thickness 0.15)
				)
				(justify left bottom)
			)
		)
		(pad "" np_thru_hole circle
			(at 0 0 180)
			(size 2.3 2.3)
			(drill 2.3)
			(layers "*.Cu" "*.Mask")
		)
	)
	(footprint "antmicro-footprints:R_0402_1005Metric"
		(layer "F.Cu")
		(at 136.15 113.15)
		(descr "Resistor SMD 0402")
		(tags "resistor SMD 0402")
		(property "Reference" "R92"
			(at 16.549997 17.25 0)
			(layer "F.SilkS")
			(effects
				(font
					(size 0.7 0.7)
					(thickness 0.15)
				)
			)
		)
		(property "Value" "R_0R_0402"
			(at -1.011843 1.772047 0)
			(layer "F.Fab")
			(effects
				(font
					(size 0.7 0.7)
					(thickness 0.15)
				)
				(justify left bottom)
			)
		)
		(property "Datasheet" "https://industrial.panasonic.com/cdbs/www-data/pdf/RDA0000/AOA0000C301.pdf"
			(at 0 0 0)
			(layer "F.Fab")
			(hide yes)
			(effects
				(font
					(size 1.27 1.27)
					(thickness 0.15)
				)
			)
		)
		(property "Description" "SMD Chip Resistor, Jumper, 0 ohm, 100 mW, 0402 [1005 Metric], Thick Film, General Purpose"
			(at 0 0 0)
			(layer "F.Fab")
			(hide yes)
			(effects
				(font
					(size 1.27 1.27)
					(thickness 0.15)
				)
			)
		)
		(property "MPN" "ERJ2GE0R00X"
			(at 0 0 0)
			(unlocked yes)
			(layer "F.Fab")
			(hide yes)
			(effects
				(font
					(size 1 1)
					(thickness 0.15)
				)
			)
		)
		(property "Manufacturer" "Panasonic"
			(at 0 0 0)
			(unlocked yes)
			(layer "F.Fab")
			(hide yes)
			(effects
				(font
					(size 1 1)
					(thickness 0.15)
				)
			)
		)
		(property "License" "Apache-2.0"
			(at 0 0 0)
			(unlocked yes)
			(layer "F.Fab")
			(hide yes)
			(effects
				(font
					(size 1 1)
					(thickness 0.15)
				)
			)
		)
		(property "Author" "Antmicro"
			(at 0 0 0)
			(unlocked yes)
			(layer "F.Fab")
			(hide yes)
			(effects
				(font
					(size 1 1)
					(thickness 0.15)
				)
			)
		)
		(property "Val" "0R"
			(at 0 0 0)
			(unlocked yes)
			(layer "F.Fab")
			(hide yes)
			(effects
				(font
					(size 1 1)
					(thickness 0.15)
				)
			)
		)
		(property "Tolerance" "~"
			(at 0 0 0)
			(unlocked yes)
			(layer "F.Fab")
			(hide yes)
			(effects
				(font
					(size 1 1)
					(thickness 0.15)
				)
			)
		)
		(property "Current" "1A"
			(at 0 0 0)
			(unlocked yes)
			(layer "F.Fab")
			(hide yes)
			(effects
				(font
					(size 1 1)
					(thickness 0.15)
				)
			)
		)
		(sheetname "/X710 DCDC converters/")
		(sheetfile "DCDC_converters_X710.kicad_sch")
		(attr smd)
		(fp_rect
			(start -0.925 -0.47)
			(end 0.925 0.47)
			(stroke
				(width 0.05)
				(type default)
			)
			(fill no)
			(layer "F.CrtYd")
		)
		(fp_rect
			(start -0.5 -0.25)
			(end 0.5 0.25)
			(stroke
				(width 0.15)
				(type solid)
			)
			(fill no)
			(layer "F.Fab")
		)
		(fp_text user "Author: Antmicro"
			(at -0.95 4.169 0)
			(layer "F.Fab")
			(effects
				(font
					(size 0.7 0.7)
					(thickness 0.15)
				)
				(justify left bottom)
			)
		)
		(fp_text user "License: Apache-2.0"
			(at -0.95 5.169 0)
			(layer "F.Fab")
			(effects
				(font
					(size 0.7 0.7)
					(thickness 0.15)
				)
				(justify left bottom)
			)
		)
		(fp_text user "${REFERENCE}"
			(at -0.95 3.168 0)
			(layer "F.Fab")
			(effects
				(font
					(size 0.7 0.7)
					(thickness 0.15)
				)
				(justify left bottom)
			)
		)
		(pad "1" smd roundrect
			(at -0.48 0)
			(size 0.59 0.64)
			(layers "F.Cu" "F.Mask" "F.Paste")
			(roundrect_rratio 0.25)
			(net 378 "/X710 DCDC converters/3V3_PG")
			(pintype "passive")
		)
		(pad "2" smd roundrect
			(at 0.48 0)
			(size 0.59 0.64)
			(layers "F.Cu" "F.Mask" "F.Paste")
			(roundrect_rratio 0.25)
			(net 382 "/X710 DCDC converters/VCCD_EN")
			(pintype "passive")
		)
	)
)
